FILE_TYPE = CONNECTIVITY;
{Allegro Design Entry HDL 16.6-p007 (v16-6-112F) 10/10/2012}
"PAGE_NUMBER" = 65;
0"NC";
1"TP_P3E_CPU1_PE2_RSR_TXN<15:0>";
2"TP_P3E_CPU1_PE2_RSR_TXP<15:0>";
3"TP_P3E_CPU1_PE2_RSR_RXN<15:0>";
4"TP_P3E_CPU1_PE2_RSR_RXP<15:0>";
5"TP_P3E_CPU1_PE2_RSR_RXP<0>";
6"TP_P3E_CPU1_PE2_RSR_RXP<1>";
7"TP_P3E_CPU1_PE2_RSR_RXP<2>";
8"TP_P3E_CPU1_PE2_RSR_RXP<3>";
9"TP_P3E_CPU1_PE2_RSR_RXN<0>";
10"TP_P3E_CPU1_PE2_RSR_RXN<1>";
11"TP_P3E_CPU1_PE2_RSR_RXN<2>";
12"TP_P3E_CPU1_PE2_RSR_RXN<3>";
13"TP_P3E_CPU1_PE2_RSR_RXP<4>";
14"TP_P3E_CPU1_PE2_RSR_RXP<5>";
15"TP_P3E_CPU1_PE2_RSR_RXP<6>";
16"TP_P3E_CPU1_PE2_RSR_RXP<7>";
17"TP_P3E_CPU1_PE2_RSR_RXP<8>";
18"TP_P3E_CPU1_PE2_RSR_RXP<9>";
19"TP_P3E_CPU1_PE2_RSR_RXP<10>";
20"TP_P3E_CPU1_PE2_RSR_RXP<11>";
21"TP_P3E_CPU1_PE2_RSR_RXP<12>";
22"TP_P3E_CPU1_PE2_RSR_RXP<13>";
23"TP_P3E_CPU1_PE2_RSR_RXP<14>";
24"TP_P3E_CPU1_PE2_RSR_RXP<15>";
25"TP_P3E_CPU1_PE2_RSR_RXN<4>";
26"TP_P3E_CPU1_PE2_RSR_RXN<5>";
27"TP_P3E_CPU1_PE2_RSR_RXN<6>";
28"TP_P3E_CPU1_PE2_RSR_RXN<7>";
29"TP_P3E_CPU1_PE2_RSR_RXN<8>";
30"TP_P3E_CPU1_PE2_RSR_RXN<9>";
31"TP_P3E_CPU1_PE2_RSR_RXN<10>";
32"TP_P3E_CPU1_PE2_RSR_RXN<11>";
33"TP_P3E_CPU1_PE2_RSR_RXN<12>";
34"TP_P3E_CPU1_PE2_RSR_RXN<13>";
35"TP_P3E_CPU1_PE2_RSR_RXN<14>";
36"TP_P3E_CPU1_PE2_RSR_RXN<15>";
37"TP_P3E_CPU1_PE2_RSR_TXP<0>";
38"TP_P3E_CPU1_PE2_RSR_TXP<1>";
39"TP_P3E_CPU1_PE2_RSR_TXP<2>";
40"TP_P3E_CPU1_PE2_RSR_TXP<3>";
41"TP_P3E_CPU1_PE2_RSR_TXN<0>";
42"TP_P3E_CPU1_PE2_RSR_TXN<1>";
43"TP_P3E_CPU1_PE2_RSR_TXN<2>";
44"TP_P3E_CPU1_PE2_RSR_TXN<3>";
45"TP_P3E_CPU1_PE2_RSR_TXP<4>";
46"TP_P3E_CPU1_PE2_RSR_TXP<5>";
47"TP_P3E_CPU1_PE2_RSR_TXP<6>";
48"TP_P3E_CPU1_PE2_RSR_TXP<7>";
49"TP_P3E_CPU1_PE2_RSR_TXP<8>";
50"TP_P3E_CPU1_PE2_RSR_TXP<9>";
51"TP_P3E_CPU1_PE2_RSR_TXP<10>";
52"TP_P3E_CPU1_PE2_RSR_TXP<11>";
53"TP_P3E_CPU1_PE2_RSR_TXP<12>";
54"TP_P3E_CPU1_PE2_RSR_TXP<13>";
55"TP_P3E_CPU1_PE2_RSR_TXP<14>";
56"TP_P3E_CPU1_PE2_RSR_TXP<15>";
57"TP_P3E_CPU1_PE2_RSR_TXN<4>";
58"TP_P3E_CPU1_PE2_RSR_TXN<5>";
59"TP_P3E_CPU1_PE2_RSR_TXN<6>";
60"TP_P3E_CPU1_PE2_RSR_TXN<7>";
61"TP_P3E_CPU1_PE2_RSR_TXN<8>";
62"TP_P3E_CPU1_PE2_RSR_TXN<9>";
63"TP_P3E_CPU1_PE2_RSR_TXN<10>";
64"TP_P3E_CPU1_PE2_RSR_TXN<11>";
65"TP_P3E_CPU1_PE2_RSR_TXN<12>";
66"TP_P3E_CPU1_PE2_RSR_TXN<13>";
67"TP_P3E_CPU1_PE2_RSR_TXN<14>";
68"TP_P3E_CPU1_PE2_RSR_TXN<15>";
%"TAP"
"1","(-5575,2125)","2","mstr_standard","I11";
;
HDL_TAP"TRUE"
BODY_TYPE"PLUMBING"
CDS_LIB"mstr_standard";
"B \NAC \NWC"3;
"S \NAC"
BN"4"25;
%"TAP"
"1","(-5575,2225)","2","mstr_standard","I12";
;
HDL_TAP"TRUE"
BODY_TYPE"PLUMBING"
CDS_LIB"mstr_standard";
"B \NAC \NWC"3;
"S \NAC"
BN"6"27;
%"TAP"
"1","(-5575,2175)","2","mstr_standard","I13";
;
HDL_TAP"TRUE"
BODY_TYPE"PLUMBING"
CDS_LIB"mstr_standard";
"B \NAC \NWC"3;
"S \NAC"
BN"5"26;
%"TAP"
"1","(-5575,2275)","2","mstr_standard","I14";
;
HDL_TAP"TRUE"
BODY_TYPE"PLUMBING"
CDS_LIB"mstr_standard";
"B \NAC \NWC"3;
"S \NAC"
BN"7"28;
%"TAP"
"1","(-5425,2025)","2","mstr_standard","I15";
;
HDL_TAP"TRUE"
BODY_TYPE"PLUMBING"
CDS_LIB"mstr_standard";
"B \NAC \NWC"4;
"S \NAC"
BN"3"8;
%"TAP"
"1","(-5425,2375)","2","mstr_standard","I16";
;
HDL_TAP"TRUE"
BODY_TYPE"PLUMBING"
CDS_LIB"mstr_standard";
"B \NAC \NWC"4;
"S \NAC"
BN"4"13;
%"TAP"
"1","(-5425,2425)","2","mstr_standard","I17";
;
HDL_TAP"TRUE"
BODY_TYPE"PLUMBING"
CDS_LIB"mstr_standard";
"B \NAC \NWC"4;
"S \NAC"
BN"5"14;
%"TAP"
"1","(-5425,2475)","2","mstr_standard","I18";
;
HDL_TAP"TRUE"
BODY_TYPE"PLUMBING"
CDS_LIB"mstr_standard";
"B \NAC \NWC"4;
"S \NAC"
BN"6"15;
%"TAP"
"1","(-5575,2625)","2","mstr_standard","I19";
;
HDL_TAP"TRUE"
BODY_TYPE"PLUMBING"
CDS_LIB"mstr_standard";
"B \NAC \NWC"3;
"S \NAC"
BN"8"29;
%"TAP"
"1","(-5575,2725)","2","mstr_standard","I20";
;
HDL_TAP"TRUE"
BODY_TYPE"PLUMBING"
CDS_LIB"mstr_standard";
"B \NAC \NWC"3;
"S \NAC"
BN"10"31;
%"TAP"
"1","(-5575,2675)","2","mstr_standard","I21";
;
HDL_TAP"TRUE"
BODY_TYPE"PLUMBING"
CDS_LIB"mstr_standard";
"B \NAC \NWC"3;
"S \NAC"
BN"9"30;
%"TAP"
"1","(-5575,2775)","2","mstr_standard","I22";
;
HDL_TAP"TRUE"
BODY_TYPE"PLUMBING"
CDS_LIB"mstr_standard";
"B \NAC \NWC"3;
"S \NAC"
BN"11"32;
%"TAP"
"1","(-5425,2525)","2","mstr_standard","I23";
;
HDL_TAP"TRUE"
BODY_TYPE"PLUMBING"
CDS_LIB"mstr_standard";
"B \NAC \NWC"4;
"S \NAC"
BN"7"16;
%"TAP"
"1","(-5425,2875)","2","mstr_standard","I24";
;
HDL_TAP"TRUE"
BODY_TYPE"PLUMBING"
CDS_LIB"mstr_standard";
"B \NAC \NWC"4;
"S \NAC"
BN"8"17;
%"TAP"
"1","(-5425,2925)","2","mstr_standard","I25";
;
HDL_TAP"TRUE"
BODY_TYPE"PLUMBING"
CDS_LIB"mstr_standard";
"B \NAC \NWC"4;
"S \NAC"
BN"9"18;
%"TAP"
"1","(-5425,2975)","2","mstr_standard","I26";
;
HDL_TAP"TRUE"
BODY_TYPE"PLUMBING"
CDS_LIB"mstr_standard";
"B \NAC \NWC"4;
"S \NAC"
BN"10"19;
%"TAP"
"1","(-5575,3125)","2","mstr_standard","I27";
;
HDL_TAP"TRUE"
BODY_TYPE"PLUMBING"
CDS_LIB"mstr_standard";
"B \NAC \NWC"3;
"S \NAC"
BN"12"33;
%"TAP"
"1","(-5575,3225)","2","mstr_standard","I28";
;
HDL_TAP"TRUE"
BODY_TYPE"PLUMBING"
CDS_LIB"mstr_standard";
"B \NAC \NWC"3;
"S \NAC"
BN"14"35;
%"TAP"
"1","(-5575,3175)","2","mstr_standard","I29";
;
HDL_TAP"TRUE"
BODY_TYPE"PLUMBING"
CDS_LIB"mstr_standard";
"B \NAC \NWC"3;
"S \NAC"
BN"13"34;
%"TAP"
"1","(-5575,1725)","2","mstr_standard","I3";
;
HDL_TAP"TRUE"
BODY_TYPE"PLUMBING"
CDS_LIB"mstr_standard";
"B \NAC \NWC"3;
"S \NAC"
BN"2"11;
%"TAP"
"1","(-5575,3275)","2","mstr_standard","I30";
;
HDL_TAP"TRUE"
BODY_TYPE"PLUMBING"
CDS_LIB"mstr_standard";
"B \NAC \NWC"3;
"S \NAC"
BN"15"36;
%"TAP"
"1","(-5425,3025)","2","mstr_standard","I31";
;
HDL_TAP"TRUE"
BODY_TYPE"PLUMBING"
CDS_LIB"mstr_standard";
"B \NAC \NWC"4;
"S \NAC"
BN"11"20;
%"TAP"
"1","(-5425,3375)","2","mstr_standard","I32";
;
HDL_TAP"TRUE"
BODY_TYPE"PLUMBING"
CDS_LIB"mstr_standard";
"B \NAC \NWC"4;
"S \NAC"
BN"12"21;
%"TAP"
"1","(-5425,3475)","2","mstr_standard","I33";
;
HDL_TAP"TRUE"
BODY_TYPE"PLUMBING"
CDS_LIB"mstr_standard";
"B \NAC \NWC"4;
"S \NAC"
BN"14"23;
%"TAP"
"1","(-5425,3425)","2","mstr_standard","I34";
;
HDL_TAP"TRUE"
BODY_TYPE"PLUMBING"
CDS_LIB"mstr_standard";
"B \NAC \NWC"4;
"S \NAC"
BN"13"22;
%"TAP"
"1","(-5425,3525)","2","mstr_standard","I35";
;
HDL_TAP"TRUE"
BODY_TYPE"PLUMBING"
CDS_LIB"mstr_standard";
"B \NAC \NWC"4;
"S \NAC"
BN"15"24;
%"TAP"
"1","(-2950,1975)","0","mstr_standard","I36";
;
HDL_TAP"TRUE"
BODY_TYPE"PLUMBING"
CDS_LIB"mstr_standard";
"B \NAC \NWC"2;
"S \NAC"
BN"2"39;
%"TAP"
"1","(-2950,1875)","0","mstr_standard","I37";
;
HDL_TAP"TRUE"
BODY_TYPE"PLUMBING"
CDS_LIB"mstr_standard";
"B \NAC \NWC"2;
"S \NAC"
BN"0"37;
%"TAP"
"1","(-2950,1925)","0","mstr_standard","I38";
;
HDL_TAP"TRUE"
BODY_TYPE"PLUMBING"
CDS_LIB"mstr_standard";
"B \NAC \NWC"2;
"S \NAC"
BN"1"38;
%"TAP"
"1","(-2800,1675)","0","mstr_standard","I39";
;
HDL_TAP"TRUE"
BODY_TYPE"PLUMBING"
CDS_LIB"mstr_standard";
"B \NAC \NWC"1;
"S \NAC"
BN"1"42;
%"TAP"
"1","(-5575,1675)","2","mstr_standard","I4";
;
HDL_TAP"TRUE"
BODY_TYPE"PLUMBING"
CDS_LIB"mstr_standard";
"B \NAC \NWC"3;
"S \NAC"
BN"1"10;
%"TAP"
"1","(-2800,1625)","0","mstr_standard","I40";
;
HDL_TAP"TRUE"
BODY_TYPE"PLUMBING"
CDS_LIB"mstr_standard";
"B \NAC \NWC"1;
"S \NAC"
BN"0"41;
%"TAP"
"1","(-2800,1725)","0","mstr_standard","I41";
;
HDL_TAP"TRUE"
BODY_TYPE"PLUMBING"
CDS_LIB"mstr_standard";
"B \NAC \NWC"1;
"S \NAC"
BN"2"43;
%"TAP"
"1","(-2800,1775)","0","mstr_standard","I42";
;
HDL_TAP"TRUE"
BODY_TYPE"PLUMBING"
CDS_LIB"mstr_standard";
"B \NAC \NWC"1;
"S \NAC"
BN"3"44;
%"TAP"
"1","(-2950,2475)","0","mstr_standard","I43";
;
HDL_TAP"TRUE"
BODY_TYPE"PLUMBING"
CDS_LIB"mstr_standard";
"B \NAC \NWC"2;
"S \NAC"
BN"6"47;
%"TAP"
"1","(-2950,2425)","0","mstr_standard","I44";
;
HDL_TAP"TRUE"
BODY_TYPE"PLUMBING"
CDS_LIB"mstr_standard";
"B \NAC \NWC"2;
"S \NAC"
BN"5"46;
%"TAP"
"1","(-2950,2375)","0","mstr_standard","I45";
;
HDL_TAP"TRUE"
BODY_TYPE"PLUMBING"
CDS_LIB"mstr_standard";
"B \NAC \NWC"2;
"S \NAC"
BN"4"45;
%"TAP"
"1","(-2950,2025)","0","mstr_standard","I46";
;
HDL_TAP"TRUE"
BODY_TYPE"PLUMBING"
CDS_LIB"mstr_standard";
"B \NAC \NWC"2;
"S \NAC"
BN"3"40;
%"TAP"
"1","(-2800,2125)","0","mstr_standard","I47";
;
HDL_TAP"TRUE"
BODY_TYPE"PLUMBING"
CDS_LIB"mstr_standard";
"B \NAC \NWC"1;
"S \NAC"
BN"4"57;
%"TAP"
"1","(-2800,2175)","0","mstr_standard","I48";
;
HDL_TAP"TRUE"
BODY_TYPE"PLUMBING"
CDS_LIB"mstr_standard";
"B \NAC \NWC"1;
"S \NAC"
BN"5"58;
%"TAP"
"1","(-2800,2225)","0","mstr_standard","I49";
;
HDL_TAP"TRUE"
BODY_TYPE"PLUMBING"
CDS_LIB"mstr_standard";
"B \NAC \NWC"1;
"S \NAC"
BN"6"59;
%"TAP"
"1","(-5575,1625)","2","mstr_standard","I5";
;
HDL_TAP"TRUE"
BODY_TYPE"PLUMBING"
CDS_LIB"mstr_standard";
"B \NAC \NWC"3;
"S \NAC"
BN"0"9;
%"TAP"
"1","(-2800,2275)","0","mstr_standard","I50";
;
HDL_TAP"TRUE"
BODY_TYPE"PLUMBING"
CDS_LIB"mstr_standard";
"B \NAC \NWC"1;
"S \NAC"
BN"7"60;
%"TAP"
"1","(-2950,2975)","0","mstr_standard","I51";
;
HDL_TAP"TRUE"
BODY_TYPE"PLUMBING"
CDS_LIB"mstr_standard";
"B \NAC \NWC"2;
"S \NAC"
BN"10"51;
%"TAP"
"1","(-2950,2925)","0","mstr_standard","I52";
;
HDL_TAP"TRUE"
BODY_TYPE"PLUMBING"
CDS_LIB"mstr_standard";
"B \NAC \NWC"2;
"S \NAC"
BN"9"50;
%"TAP"
"1","(-2950,2875)","0","mstr_standard","I53";
;
HDL_TAP"TRUE"
BODY_TYPE"PLUMBING"
CDS_LIB"mstr_standard";
"B \NAC \NWC"2;
"S \NAC"
BN"8"49;
%"TAP"
"1","(-2950,2525)","0","mstr_standard","I54";
;
HDL_TAP"TRUE"
BODY_TYPE"PLUMBING"
CDS_LIB"mstr_standard";
"B \NAC \NWC"2;
"S \NAC"
BN"7"48;
%"TAP"
"1","(-2800,2625)","0","mstr_standard","I55";
;
HDL_TAP"TRUE"
BODY_TYPE"PLUMBING"
CDS_LIB"mstr_standard";
"B \NAC \NWC"1;
"S \NAC"
BN"8"61;
%"TAP"
"1","(-2800,2725)","0","mstr_standard","I56";
;
HDL_TAP"TRUE"
BODY_TYPE"PLUMBING"
CDS_LIB"mstr_standard";
"B \NAC \NWC"1;
"S \NAC"
BN"10"63;
%"TAP"
"1","(-2800,2675)","0","mstr_standard","I57";
;
HDL_TAP"TRUE"
BODY_TYPE"PLUMBING"
CDS_LIB"mstr_standard";
"B \NAC \NWC"1;
"S \NAC"
BN"9"62;
%"TAP"
"1","(-2800,2775)","0","mstr_standard","I58";
;
HDL_TAP"TRUE"
BODY_TYPE"PLUMBING"
CDS_LIB"mstr_standard";
"B \NAC \NWC"1;
"S \NAC"
BN"11"64;
%"TAP"
"1","(-2950,3525)","0","mstr_standard","I59";
;
HDL_TAP"TRUE"
BODY_TYPE"PLUMBING"
CDS_LIB"mstr_standard";
"B \NAC \NWC"2;
"S \NAC"
BN"15"56;
%"TAP"
"1","(-5575,1775)","2","mstr_standard","I6";
;
HDL_TAP"TRUE"
BODY_TYPE"PLUMBING"
CDS_LIB"mstr_standard";
"B \NAC \NWC"3;
"S \NAC"
BN"3"12;
%"TAP"
"1","(-2950,3475)","0","mstr_standard","I60";
;
HDL_TAP"TRUE"
BODY_TYPE"PLUMBING"
CDS_LIB"mstr_standard";
"B \NAC \NWC"2;
"S \NAC"
BN"14"55;
%"TAP"
"1","(-2950,3425)","0","mstr_standard","I61";
;
HDL_TAP"TRUE"
BODY_TYPE"PLUMBING"
CDS_LIB"mstr_standard";
"B \NAC \NWC"2;
"S \NAC"
BN"13"54;
%"TAP"
"1","(-2950,3375)","0","mstr_standard","I62";
;
HDL_TAP"TRUE"
BODY_TYPE"PLUMBING"
CDS_LIB"mstr_standard";
"B \NAC \NWC"2;
"S \NAC"
BN"12"53;
%"TAP"
"1","(-2950,3025)","0","mstr_standard","I63";
;
HDL_TAP"TRUE"
BODY_TYPE"PLUMBING"
CDS_LIB"mstr_standard";
"B \NAC \NWC"2;
"S \NAC"
BN"11"52;
%"TAP"
"1","(-2800,3125)","0","mstr_standard","I64";
;
HDL_TAP"TRUE"
BODY_TYPE"PLUMBING"
CDS_LIB"mstr_standard";
"B \NAC \NWC"1;
"S \NAC"
BN"12"65;
%"TAP"
"1","(-2800,3175)","0","mstr_standard","I65";
;
HDL_TAP"TRUE"
BODY_TYPE"PLUMBING"
CDS_LIB"mstr_standard";
"B \NAC \NWC"1;
"S \NAC"
BN"13"66;
%"TAP"
"1","(-2800,3275)","0","mstr_standard","I66";
;
HDL_TAP"TRUE"
BODY_TYPE"PLUMBING"
CDS_LIB"mstr_standard";
"B \NAC \NWC"1;
"S \NAC"
BN"15"68;
%"TAP"
"1","(-2800,3225)","0","mstr_standard","I67";
;
HDL_TAP"TRUE"
BODY_TYPE"PLUMBING"
CDS_LIB"mstr_standard";
"B \NAC \NWC"1;
"S \NAC"
BN"14"67;
%"SKX_EXT_B"
"11","(-4150,2575)","0","chpset_lib","I68";
;
CDS_SEC"11"
CDS_LOCATION"U2D1"
SEC"11"
CDS_LIB"chpset_lib"
SEC_TYPE"BGA1"
PACK_TYPE"BGA1"
MATERIAL"IC"
PART_NUMBER"TBD"
LOCATION"U2D1";
"PE2_TX_DP<0>"
$PN"CW4"37;
"PE2_TX_DP<1>"
$PN"CU2"38;
"PE2_TX_DP<2>"
$PN"CR2"39;
"PE2_TX_DP<3>"
$PN"CP3"40;
"PE2_TX_DP<4>"
$PN"CK1"45;
"PE2_TX_DP<5>"
$PN"CK3"46;
"PE2_TX_DP<6>"
$PN"CE2"47;
"PE2_TX_DP<7>"
$PN"CE4"48;
"PE2_TX_DP<8>"
$PN"CD3"49;
"PE2_TX_DP<9>"
$PN"BY3"50;
"PE2_TX_DP<10>"
$PN"BY5"51;
"PE2_TX_DP<11>"
$PN"BV3"52;
"PE2_TX_DP<12>"
$PN"BR4"53;
"PE2_TX_DP<13>"
$PN"BN4"54;
"PE2_TX_DP<14>"
$PN"BM3"55;
"PE2_TX_DP<15>"
$PN"BK5"56;
"PE2_TX_DN<0>"
$PN"CY3"41;
"PE2_TX_DN<1>"
$PN"CV3"42;
"PE2_TX_DN<2>"
$PN"CT1"43;
"PE2_TX_DN<3>"
$PN"CT3"44;
"PE2_TX_DN<4>"
$PN"CM1"57;
"PE2_TX_DN<5>"
$PN"CL2"58;
"PE2_TX_DN<6>"
$PN"CG2"59;
"PE2_TX_DN<7>"
$PN"CF3"60;
"PE2_TX_DN<8>"
$PN"CC2"61;
"PE2_TX_DN<9>"
$PN"CB3"62;
"PE2_TX_DN<10>"
$PN"CA4"63;
"PE2_TX_DN<11>"
$PN"BW4"64;
"PE2_TX_DN<12>"
$PN"BU4"65;
"PE2_TX_DN<13>"
$PN"BP5"66;
"PE2_TX_DN<14>"
$PN"BL4"67;
"PE2_TX_DN<15>"
$PN"BM5"68;
"PE2_RX_DP<0>"
$PN"CR8"5;
"PE2_RX_DP<1>"
$PN"CM9"6;
"PE2_RX_DP<2>"
$PN"CN8"7;
"PE2_RX_DP<3>"
$PN"CL6"8;
"PE2_RX_DP<4>"
$PN"CH7"13;
"PE2_RX_DP<5>"
$PN"CF7"14;
"PE2_RX_DP<6>"
$PN"CD7"15;
"PE2_RX_DP<7>"
$PN"CC8"16;
"PE2_RX_DP<8>"
$PN"BV9"17;
"PE2_RX_DP<9>"
$PN"BW8"18;
"PE2_RX_DP<10>"
$PN"BU6"19;
"PE2_RX_DP<11>"
$PN"BP7"20;
"PE2_RX_DP<12>"
$PN"BP9"21;
"PE2_RX_DP<13>"
$PN"BM7"22;
"PE2_RX_DP<14>"
$PN"BJ8"23;
"PE2_RX_DP<15>"
$PN"BJ10"24;
"PE2_RX_DN<0>"
$PN"CT9"9;
"PE2_RX_DN<1>"
$PN"CP9"10;
"PE2_RX_DN<2>"
$PN"CP7"11;
"PE2_RX_DN<3>"
$PN"CM7"12;
"PE2_RX_DN<4>"
$PN"CK7"25;
"PE2_RX_DN<5>"
$PN"CG8"26;
"PE2_RX_DN<6>"
$PN"CE6"27;
"PE2_RX_DN<7>"
$PN"CE8"28;
"PE2_RX_DN<8>"
$PN"BY9"29;
"PE2_RX_DN<9>"
$PN"BY7"30;
"PE2_RX_DN<10>"
$PN"BV7"31;
"PE2_RX_DN<11>"
$PN"BT7"32;
"PE2_RX_DN<12>"
$PN"BR8"33;
"PE2_RX_DN<13>"
$PN"BN8"34;
"PE2_RX_DN<14>"
$PN"BL8"35;
"PE2_RX_DN<15>"
$PN"BK9"36;
%"TAP"
"1","(-5425,1975)","2","mstr_standard","I7";
;
HDL_TAP"TRUE"
BODY_TYPE"PLUMBING"
CDS_LIB"mstr_standard";
"B \NAC \NWC"4;
"S \NAC"
BN"2"7;
%"TAP"
"1","(-5425,1925)","2","mstr_standard","I8";
;
HDL_TAP"TRUE"
BODY_TYPE"PLUMBING"
CDS_LIB"mstr_standard";
"B \NAC \NWC"4;
"S \NAC"
BN"1"6;
%"TAP"
"1","(-5425,1875)","2","mstr_standard","I9";
;
HDL_TAP"TRUE"
BODY_TYPE"PLUMBING"
CDS_LIB"mstr_standard";
"B \NAC \NWC"4;
"S \NAC"
BN"0"5;
END.
